FILE_TYPE = MACRO_DRAWING;
SET COLOR_WIRE YELLOW;
SET COLOR_PROP ORANGE;
SET COLOR_DOT WHITE;
SET COLOR_ARC YELLOW;
SET COLOR_BODY GREEN;
SET COLOR_NOTE PURPLE;
SET PROP_DISPLAY VALUE;
SET PAGE_NUMBER P139;
FORCEADD QUANTA_TITLE_BLOCK_C..1
(-100 100);
FORCEPROP 1 LAST CUSTOM_TXT_CDS <NAME_2>
J 0
(-3275 150);
FORCEPROP 1 LAST CUSTOM_TXT_CDS <NAME_1>
J 0
(-3275 275);
FORCEPROP 1 LAST CUSTOM_TXT_CDS <Q_NUMBER>
J 0
(-1503 203);
DISPLAY 1.212766 (-1503 203);
FORCEPROP 1 LAST CUSTOM_TXT_CDS <Q_PROJ>
J 0
(-2482 202);
DISPLAY 1.212766 (-2482 202);
FORCEPROP 1 LAST CUSTOM_TXT_CDS <Q_REV>
J 0
(-284 203);
DISPLAY 1.212766 (-284 203);
FORCEPROP 1 LAST CUSTOM_TXT_CDS <CON_LAST_MODIFIED>
J 0
(-1985 115);
DISPLAY 0.978723 (-1985 115);
FORCEPROP 1 LAST CUSTOM_TXT_CDS <CON_PAGE_NUM> OF <CON_TOTAL_PAGES>
J 0
(-546 118);
DISPLAY 0.978723 (-546 118);
FORCEPROP 1 LAST Q_DEPT BU9
J 1
(-3863 149);
DISPLAY 1.957447 (-3863 149);
PAINT GREEN (-3863 149);
FORCEPROP 1 LAST Q_TITLE INTRUSION DETECTION
J 0
(-9350 200);
DISPLAY 2.446809 (-9350 200);
PAINT GREEN (-9350 200);
FORCEPROP 2 LAST PAGE_BORDER TRUE
J 0
(-7990 5350);
DISPLAY 0.638298 (-7990 5350);
PAINT PINK (-7990 5350);
DISPLAY INVISIBLE (-7990 5350);
FORCEPROP 1 LAST CDS_LMAN_SYM_OUTLINE -9475,6775,100,-125
J 0
(-100 100);
DISPLAY 0.468085 (-100 100);
PAINT GREEN (-100 100);
DISPLAY INVISIBLE (-100 100);
FORCEPROP 2 LAST CDS_LIB pure_quanta
J 0
(-100 100);
DISPLAY INVISIBLE (-100 100);
FORCEPROP 1 LAST COMMENT_BODY TRUE
J 0
(-88 87);
DISPLAY 0.978723 (-88 87);
PAINT GREEN (-88 87);
DISPLAY INVISIBLE (-88 87);
FORCEPROP 2 LAST CDS_XR_PAGE_TITLE CR-139 : @T6G_MB_LIB.T6G(SCH_1):PAGE139
J 0
(-7990 5350);
DISPLAY 0.638298 (-7990 5350);
PAINT PINK (-7990 5350);
DISPLAY INVISIBLE (-7990 5350);
FORCEPROP 2 LAST CUSTOM_TXT_CDS <XR_PAGE_TITLE>
J 0
(-7990 5350);
DISPLAY 0.638298 (-7990 5350);
PAINT PINK (-7990 5350);
DISPLAY INVISIBLE (-7990 5350);
FORCEPROP 0 LAST CDS_CON_LAST_MODIFIED Wed Mar 09 19:13:03 2022
J 0
(-1985 115);
DISPLAY INVISIBLE (-1985 115);
QUIT
